;LEADER: 12 
;HEADER: 
;CODE  : ASCII 
;FILE  : R4006-B0001-02_R01-bd-1-7.drl for backdrilling ... from layer TOP to layer L07_GND3
;DESIGN: R4006-B0001-02_R01.brd
;MUST-NOT-CUT-LAYER = L08_SIG2,  MAX_DRILL_DEPTH = 49.80 MILS,  MFG_STUB_LENGTH = 0.00 MILS
;T11 BackdrillSize 1. = 16.000000 Tolerance = +0.000000/-0.000000 NON_PLATED MILS Quantity = 10
%
G90
T11
X0000240508Y0000073100
X0000240508Y0000069900
X0000312500Y0000087500
X0000314763Y0000085237
X0000281855Y0000076300
X0000285055Y0000076300
X0000266707Y0000076300
X0000269907Y0000076300
X0000247022Y0000076300
X0000250222Y0000076300
M30
